# T6G (Grand Teton) — schematic netlist excerpt (pin names and nets, part order shuffled) for the footprints in the layout excerpt that follows; sources: Cadence DE-HDL packaged netlist, KiCad conversion of 04192023_DAF0TMB3IC0_F0TG_MB_C_brd_V02_OCP.brd

J16  SCONN288_DDR506112002KQ  IO  pkg DDR288S_1-1VXC  page 92
  VIN_BULK0  = P12V_MEM_CPU0
  RFU0  = NC
  VIN_MGMT  = P3V3_AUX
  HSCL  = I3C_SPD_DDRG_CPU0_SCL
  HSDA  = I3C_SPD_DDRG_CPU0_SDA
  VSS0  = GND
  DQ0_A  = M_G_CPU0_SA_DQ<0>
  VSS1  = GND
  DQ1_A  = M_G_CPU0_SA_DQ<1>
  VSS2  = GND
  DQS0_A_T  = M_G_CPU0_SA_DQS_DP<0>
  DQS0_A_C  = M_G_CPU0_SA_DQS_DN<0>
  VSS3  = GND
  DQ4_A  = M_G_CPU0_SA_DQ<4>
  VSS4  = GND
  DQ5_A  = M_G_CPU0_SA_DQ<5>
  VSS5  = GND
  DQ8_A  = M_G_CPU0_SA_DQ<8>
  VSS6  = GND
  DQ9_A  = M_G_CPU0_SA_DQ<9>
  VSS7  = GND
  DQS1_A_T  = M_G_CPU0_SA_DQS_DP<1>
  DQS1_A_C  = M_G_CPU0_SA_DQS_DN<1>
  VSS8  = GND
  DQ12_A  = M_G_CPU0_SA_DQ<12>
  VSS9  = GND
  DQ13_A  = M_G_CPU0_SA_DQ<13>
  VSS10  = GND
  DQ16_A  = M_G_CPU0_SA_DQ<16>
  VSS11  = GND
  DQ17_A  = M_G_CPU0_SA_DQ<17>
  VSS12  = GND
  DQS2_A_T  = M_G_CPU0_SA_DQS_DP<2>
  DQS2_A_C  = M_G_CPU0_SA_DQS_DN<2>
  VSS13  = GND
  DQ20_A  = M_G_CPU0_SA_DQ<20>
  VSS14  = GND
  DQ21_A  = M_G_CPU0_SA_DQ<21>
  VSS15  = GND
  DQ24_A  = M_G_CPU0_SA_DQ<24>
  VSS16  = GND
  DQ25_A  = M_G_CPU0_SA_DQ<25>
  VSS17  = GND
  DQS3_A_T  = M_G_CPU0_SA_DQS_DP<3>
  DQS3_A_C  = M_G_CPU0_SA_DQS_DN<3>
  VSS18  = GND
  DQ28_A  = M_G_CPU0_SA_DQ<28>
  VSS19  = GND
  DQ29_A  = M_G_CPU0_SA_DQ<29>
  VSS20  = GND
  CB0_A  = M_G_CPU0_SA_CB<0>
  VSS21  = GND
  CB1_A  = M_G_CPU0_SA_CB<1>
  VSS22  = GND
  DQS4_A_T  = M_G_CPU0_SA_DQS_DP<4>
  DQS4_A_C  = M_G_CPU0_SA_DQS_DN<4>
  VSS23  = GND
  CB4_A  = M_G_CPU0_SA_CB<4>
  VSS24  = GND
  CB5_A  = M_G_CPU0_SA_CB<5>
  VSS25  = GND
  ALERT_N  = M_G_CPU0_ALERT_N
  VSS26  = GND
  CS0_A_N  = M_G_CPU0_SA_CS_N<0>
  VSS27  = GND
  CA0_A  = M_G_CPU0_SA_CA<0>
  VSS28  = GND
  CA2_A  = M_G_CPU0_SA_CA<2>
  VSS29  = GND
  CA4_A  = M_G_CPU0_SA_CA<4>
  VSS30  = GND
  CA6_A  = M_G_CPU0_SA_CA<6>
  VSS31  = GND
  PAR_A  = M_G_CPU0_SA_PAR
  VSS32  = GND
  CA0_B  = M_G_CPU0_SB_CA<0>
  VSS33  = GND
  CA2_B  = M_G_CPU0_SB_CA<2>
  VSS34  = GND
  CA4_B  = M_G_CPU0_SB_CA<4>
  VSS35  = GND
  CA6_B  = M_G_CPU0_SB_CA<6>
  VSS36  = GND
  CS0_B_N  = M_G_CPU0_SB_CS_N<0>
  VSS37  = GND
  \lbd||rsp_a_n\  = M_G_CPU0_SA_RSP<0>
  \lbs||rsp_b_n\  = M_G_CPU0_SB_RSP<0>
  VSS38  = GND
  CB4_B  = M_G_CPU0_SB_CB<4>
  VSS39  = GND
  CB5_B  = M_G_CPU0_SB_CB<5>
  VSS40  = GND
  \dqs9_b_t||tdqs9_b_t||dbi4_b_n\  = M_G_CPU0_SB_DQS_DP<9>
  \dqs9_b_c||tdqs9_b_c\  = M_G_CPU0_SB_DQS_DN<9>
  VSS41  = GND
  CB0_B  = M_G_CPU0_SB_CB<0>
  VSS42  = GND
  CB1_B  = M_G_CPU0_SB_CB<1>
  VSS43  = GND
  DQ0_B  = M_G_CPU0_SB_DQ<0>
  VSS44  = GND
  DQ1_B  = M_G_CPU0_SB_DQ<1>
  VSS45  = GND
  DQS0_B_T  = M_G_CPU0_SB_DQS_DP<0>
  DQS0_B_C  = M_G_CPU0_SB_DQS_DN<0>
  VSS46  = GND
  DQ4_B  = M_G_CPU0_SB_DQ<4>
  VSS47  = GND
  DQ5_B  = M_G_CPU0_SB_DQ<5>
  VSS48  = GND
  DQ8_B  = M_G_CPU0_SB_DQ<8>
  VSS49  = GND
  DQ9_B  = M_G_CPU0_SB_DQ<9>
  VSS50  = GND
  DQS1_B_T  = M_G_CPU0_SB_DQS_DP<1>
  DQS1_B_C  = M_G_CPU0_SB_DQS_DN<1>
  VSS51  = GND
  DQ12_B  = M_G_CPU0_SB_DQ<12>
  VSS52  = GND
  DQ13_B  = M_G_CPU0_SB_DQ<13>
  VSS53  = GND
  DQ16_B  = M_G_CPU0_SB_DQ<16>
  VSS54  = GND
  DQ17_B  = M_G_CPU0_SB_DQ<17>
  VSS55  = GND
  DQS2_B_T  = M_G_CPU0_SB_DQS_DP<2>
  DQS2_B_C  = M_G_CPU0_SB_DQS_DN<2>
  VSS56  = GND
  DQ20_B  = M_G_CPU0_SB_DQ<20>
  VSS57  = GND
  DQ21_B  = M_G_CPU0_SB_DQ<21>
  VSS58  = GND
  DQ24_B  = M_G_CPU0_SB_DQ<24>
  VSS59  = GND
  DQ25_B  = M_G_CPU0_SB_DQ<25>
  VSS60  = GND
  DQS3_B_T  = M_G_CPU0_SB_DQS_DP<3>
  DQS3_B_C  = M_G_CPU0_SB_DQS_DN<3>
  VSS61  = GND
  DQ28_B  = M_G_CPU0_SB_DQ<28>
  VSS62  = GND
  DQ29_B  = M_G_CPU0_SB_DQ<29>
  VSS63  = GND
  RFU1  = NC
  VIN_BULK1  = P12V_MEM_CPU0
  VIN_BULK2  = P12V_MEM_CPU0
  \pwr_good||fail_n\  = PWRGD_CHG_CPU0_DIMM0
  HAS  = PD_CHG_CPU0_DIMM0_SAA
  RFU2  = NC
  RFU3  = NC
  VSS64  = GND
  DQ2_A  = M_G_CPU0_SA_DQ<2>
  VSS65  = GND
  DQ3_A  = M_G_CPU0_SA_DQ<3>
  VSS66  = GND
  \dqs5_a_c||tdqs5_a_c||dqs5_a_t||tdqs5_a_t\  = M_G_CPU0_SA_DQS_DN<5>
  \dqs5_a_t||tdqs5_a_t\  = M_G_CPU0_SA_DQS_DP<5>
  VSS67  = GND
  DQ6_A  = M_G_CPU0_SA_DQ<6>
  VSS68  = GND
  DQ7_A  = M_G_CPU0_SA_DQ<7>
  VSS69  = GND
  DQ10_A  = M_G_CPU0_SA_DQ<10>
  VSS70  = GND
  DQ11_A  = M_G_CPU0_SA_DQ<11>
  VSS71  = GND
  \dqs6_a_c||tdqs6_a_c||dqs6_a_t||tdqs6_a_t\  = M_G_CPU0_SA_DQS_DN<6>
  \dqs6_a_t||tdqs6_a_t\  = M_G_CPU0_SA_DQS_DP<6>
  VSS72  = GND
  DQ14_A  = M_G_CPU0_SA_DQ<14>
  VSS73  = GND
  DQ15_A  = M_G_CPU0_SA_DQ<15>
  VSS74  = GND
  DQ18_A  = M_G_CPU0_SA_DQ<18>
  VSS75  = GND
  DQ19_A  = M_G_CPU0_SA_DQ<19>
  VSS76  = GND
  \dqs7_a_c||tdqs7_a_c\  = M_G_CPU0_SA_DQS_DN<7>
  \dqs7_a_t||tdqs7_a_t\  = M_G_CPU0_SA_DQS_DP<7>
  VSS77  = GND
  DQ22_A  = M_G_CPU0_SA_DQ<22>
  VSS78  = GND
  DQ23_A  = M_G_CPU0_SA_DQ<23>
  VSS79  = GND
  DQ26_A  = M_G_CPU0_SA_DQ<26>
  VSS80  = GND
  DQ27_A  = M_G_CPU0_SA_DQ<27>
  VSS81  = GND
  \dqs8_a_c||tdqs8_a_c\  = M_G_CPU0_SA_DQS_DN<8>
  \dqs8_a_t||tdqs8_a_t\  = M_G_CPU0_SA_DQS_DP<8>
  VSS82  = GND
  DQ30_A  = M_G_CPU0_SA_DQ<30>
  VSS83  = GND
  DQ31_A  = M_G_CPU0_SA_DQ<31>
  VSS84  = GND
  CB2_A  = M_G_CPU0_SA_CB<2>
  VSS85  = GND
  CB3_A  = M_G_CPU0_SA_CB<3>
  VSS86  = GND
  \dqs9_a_c||tdqs9_a_c\  = M_G_CPU0_SA_DQS_DN<9>
  \dqs9_a_t||tdqs9_a_t\  = M_G_CPU0_SA_DQS_DP<9>
  VSS87  = GND
  CB6_A  = M_G_CPU0_SA_CB<6>
  VSS88  = GND
  CB7_A  = M_G_CPU0_SA_CB<7>
  VSS89  = GND
  RESET_N  = M_G_CPU0_RESET_N
  VSS90  = GND
  CS1_A_N  = M_G_CPU0_SA_CS_N<1>
  VSS91  = GND
  CA1_A  = M_G_CPU0_SA_CA<1>
  VSS92  = GND
  CA3_A  = M_G_CPU0_SA_CA<3>
  VSS93  = GND
  CA5_A  = M_G_CPU0_SA_CA<5>
  VSS94  = GND
  CK_T  = M_G_CPU0_CLK_DP<0>
  CK_C  = M_G_CPU0_CLK_DN<0>
  VSS95  = GND
  RFU4  = NC
  CA1_B  = M_G_CPU0_SB_CA<1>
  VSS96  = GND
  CA3_B  = M_G_CPU0_SB_CA<3>
  VSS97  = GND
  CA5_B  = M_G_CPU0_SB_CA<5>
  VSS98  = GND
  PAR_B  = M_G_CPU0_SB_PAR
  VSS99  = GND
  CS1_B_N  = M_G_CPU0_SB_CS_N<1>
  VSS100  = GND
  RFU5  = NC
  RFU6  = NC
  VSS101  = GND
  CB6_B  = M_G_CPU0_SB_CB<6>
  VSS102  = GND
  CB7_B  = M_G_CPU0_SB_CB<7>
  VSS103  = GND
  DQS4_B_C  = M_G_CPU0_SB_DQS_DN<4>
  DQS4_B_T  = M_G_CPU0_SB_DQS_DP<4>
  VSS104  = GND
  CB2_B  = M_G_CPU0_SB_CB<2>
  VSS105  = GND
  CB3_B  = M_G_CPU0_SB_CB<3>
  VSS106  = GND
  DQ2_B  = M_G_CPU0_SB_DQ<2>
  VSS107  = GND
  DQ3_B  = M_G_CPU0_SB_DQ<3>
  VSS108  = GND
  \dqs5_b_c||tdqs5_b_c\  = M_G_CPU0_SB_DQS_DN<5>
  \dqs5_b_t||tdqs5_b_t\  = M_G_CPU0_SB_DQS_DP<5>
  VSS109  = GND
  DQ6_B  = M_G_CPU0_SB_DQ<6>
  VSS110  = GND
  DQ7_B  = M_G_CPU0_SB_DQ<7>
  VSS111  = GND
  DQ10_B  = M_G_CPU0_SB_DQ<10>
  VSS112  = GND
  DQ11_B  = M_G_CPU0_SB_DQ<11>
  VSS113  = GND
  \dqs6_b_c||tdqs6_b_c\  = M_G_CPU0_SB_DQS_DN<6>
  \dqs6_b_t||tdqs6_b_t\  = M_G_CPU0_SB_DQS_DP<6>
  VSS114  = GND
  DQ14_B  = M_G_CPU0_SB_DQ<14>
  VSS115  = GND
  DQ15_B  = M_G_CPU0_SB_DQ<15>
  VSS116  = GND
  DQ18_B  = M_G_CPU0_SB_DQ<18>
  VSS117  = GND
  DQ19_B  = M_G_CPU0_SB_DQ<19>
  VSS118  = GND
  \dqs7_b_c||tdqs7_b_c\  = M_G_CPU0_SB_DQS_DN<7>
  \dqs7_b_t||tdqs7_b_t\  = M_G_CPU0_SB_DQS_DP<7>
  VSS119  = GND
  DQ22_B  = M_G_CPU0_SB_DQ<22>
  VSS120  = GND
  DQ23_B  = M_G_CPU0_SB_DQ<23>
  VSS121  = GND
  DQ26_B  = M_G_CPU0_SB_DQ<26>
  VSS122  = GND
  DQ27_B  = M_G_CPU0_SB_DQ<27>
  VSS123  = GND
  \dqs8_b_c||tdqs8_b_c\  = M_G_CPU0_SB_DQS_DN<8>
  \dqs8_b_t||tdqs8_b_t\  = M_G_CPU0_SB_DQS_DP<8>
  VSS124  = GND
  DQ30_B  = M_G_CPU0_SB_DQ<30>
  VSS125  = GND
  DQ31_B  = M_G_CPU0_SB_DQ<31>
  VSS126  = GND
  G1  = GND
  G2  = GND
  G3  = GND

(kicad_pcb
	(version 20260206)
	(generator "pcbnew")
	(generator_version "10.0")
	(general
		(thickness 1.6)
		(legacy_teardrops no)
	)
	(paper "A4")
	(title_block
		(title "04192023_DAF0TMB3IC0_F0TG_MB_C_brd_V02_OCP.brd")
		(comment 1 "Grand Teton / footprint 1808 of 8354 (J16), pads 93-138 of 291")
	)
	(layers
		(0 "F.Cu" signal "TOP")
		(4 "In1.Cu" signal "GND")
		(6 "In2.Cu" signal "IN1")
		(8 "In3.Cu" signal "GND1")
		(10 "In4.Cu" signal "IN2")
		(12 "In5.Cu" signal "GND2")
		(14 "In6.Cu" signal "IN3")
		(16 "In7.Cu" signal "GND3")
		(18 "In8.Cu" signal "VCC")
		(20 "In9.Cu" signal "VCC1")
		(22 "In10.Cu" signal "GND4")
		(24 "In11.Cu" signal "IN4")
		(26 "In12.Cu" signal "GND5")
		(28 "In13.Cu" signal "IN5")
		(30 "In14.Cu" signal "GND6")
		(32 "In15.Cu" signal "IN6")
		(34 "In16.Cu" signal "GND7")
		(2 "B.Cu" signal "BOTTOM")
		(9 "F.Adhes" user "F.Adhesive")
		(11 "B.Adhes" user "B.Adhesive")
		(13 "F.Paste" user "Package Geometry/Pastemask Top")
		(15 "B.Paste" user "Package Geometry/Pastemask Bottom")
		(5 "F.SilkS" user "Ref Des/Silkscreen Top")
		(7 "B.SilkS" user "Ref Des/Silkscreen Bottom")
		(1 "F.Mask" user "Board Geometry/Soldermask Top")
		(3 "B.Mask" user "Board Geometry/Soldermask Bottom")
		(17 "Dwgs.User" user "User.Drawings")
		(19 "Cmts.User" user "User.Comments")
		(21 "Eco1.User" user "User.Eco1")
		(23 "Eco2.User" user "User.Eco2")
		(25 "Edge.Cuts" user "Board Geometry/Outline")
		(27 "Margin" user)
		(31 "F.CrtYd" user "Package Geometry/Place Bound Top")
		(29 "B.CrtYd" user "Package Geometry/Place Bound Bottom")
		(35 "F.Fab" user "Ref Des/Assembly Top")
		(33 "B.Fab" user "Ref Des/Assembly Bottom")
	)
	(footprint ""
		(layer "F.Cu")
		(at 414.418018 -255.560068 180)
		(property "Reference" "J16"
			(at 1.474216 81.889092 0)
			(unlocked yes)
			(layer "F.SilkS")
			(effects
				(font
					(size 0.7874 0.5842)
					(thickness 0.1524)
				)
			)
		)
		(property "Value" ""
			(at 0 0 180)
			(layer "F.Fab")
			(effects
				(font
					(size 1.27 1.27)
				)
			)
		)
		(duplicate_pad_numbers_are_jumpers no)
		(pad "93" smd rect
			(at -2.050034 19.975068 90)
			(size 0.519938 1.4986)
			(layers "F.Cu" "F.Mask" "F.Paste")
			(net "M_G_CPU0_SB_DQS_DP<9>")
		)
		(pad "94" smd rect
			(at -2.050034 20.824952 90)
			(size 0.519938 1.4986)
			(layers "F.Cu" "F.Mask" "F.Paste")
			(net "M_G_CPU0_SB_DQS_DN<9>")
		)
		(pad "95" smd rect
			(at -2.050034 21.67509 90)
			(size 0.519938 1.4986)
			(layers "F.Cu" "F.Mask" "F.Paste")
			(net "GND")
		)
		(pad "96" smd rect
			(at -2.050034 22.524974 90)
			(size 0.519938 1.4986)
			(layers "F.Cu" "F.Mask" "F.Paste")
			(net "M_G_CPU0_SB_CB<0>")
		)
		(pad "97" smd rect
			(at -2.050034 23.375112 90)
			(size 0.519938 1.4986)
			(layers "F.Cu" "F.Mask" "F.Paste")
			(net "GND")
		)
		(pad "98" smd rect
			(at -2.050034 24.224996 90)
			(size 0.519938 1.4986)
			(layers "F.Cu" "F.Mask" "F.Paste")
			(net "M_G_CPU0_SB_CB<1>")
		)
		(pad "99" smd rect
			(at -2.050034 25.07488 90)
			(size 0.519938 1.4986)
			(layers "F.Cu" "F.Mask" "F.Paste")
			(net "GND")
		)
		(pad "100" smd rect
			(at -2.050034 25.925018 90)
			(size 0.519938 1.4986)
			(layers "F.Cu" "F.Mask" "F.Paste")
			(net "M_G_CPU0_SB_DQ<0>")
		)
		(pad "101" smd rect
			(at -2.050034 26.774902 90)
			(size 0.519938 1.4986)
			(layers "F.Cu" "F.Mask" "F.Paste")
			(net "GND")
		)
		(pad "102" smd rect
			(at -2.050034 27.62504 90)
			(size 0.519938 1.4986)
			(layers "F.Cu" "F.Mask" "F.Paste")
			(net "M_G_CPU0_SB_DQ<1>")
		)
		(pad "103" smd rect
			(at -2.050034 28.474924 90)
			(size 0.519938 1.4986)
			(layers "F.Cu" "F.Mask" "F.Paste")
			(net "GND")
		)
		(pad "104" smd rect
			(at -2.050034 29.325062 90)
			(size 0.519938 1.4986)
			(layers "F.Cu" "F.Mask" "F.Paste")
			(net "M_G_CPU0_SB_DQS_DP<0>")
		)
		(pad "105" smd rect
			(at -2.050034 30.174946 90)
			(size 0.519938 1.4986)
			(layers "F.Cu" "F.Mask" "F.Paste")
			(net "M_G_CPU0_SB_DQS_DN<0>")
		)
		(pad "106" smd rect
			(at -2.050034 31.025084 90)
			(size 0.519938 1.4986)
			(layers "F.Cu" "F.Mask" "F.Paste")
			(net "GND")
		)
		(pad "107" smd rect
			(at -2.050034 31.874968 90)
			(size 0.519938 1.4986)
			(layers "F.Cu" "F.Mask" "F.Paste")
			(net "M_G_CPU0_SB_DQ<4>")
		)
		(pad "108" smd rect
			(at -2.050034 32.725106 90)
			(size 0.519938 1.4986)
			(layers "F.Cu" "F.Mask" "F.Paste")
			(net "GND")
		)
		(pad "109" smd rect
			(at -2.050034 33.57499 90)
			(size 0.519938 1.4986)
			(layers "F.Cu" "F.Mask" "F.Paste")
			(net "M_G_CPU0_SB_DQ<5>")
		)
		(pad "110" smd rect
			(at -2.050034 34.425128 90)
			(size 0.519938 1.4986)
			(layers "F.Cu" "F.Mask" "F.Paste")
			(net "GND")
		)
		(pad "111" smd rect
			(at -2.050034 35.275012 90)
			(size 0.519938 1.4986)
			(layers "F.Cu" "F.Mask" "F.Paste")
			(net "M_G_CPU0_SB_DQ<8>")
		)
		(pad "112" smd rect
			(at -2.050034 36.124896 90)
			(size 0.519938 1.4986)
			(layers "F.Cu" "F.Mask" "F.Paste")
			(net "GND")
		)
		(pad "113" smd rect
			(at -2.050034 36.975034 90)
			(size 0.519938 1.4986)
			(layers "F.Cu" "F.Mask" "F.Paste")
			(net "M_G_CPU0_SB_DQ<9>")
		)
		(pad "114" smd rect
			(at -2.050034 37.824918 90)
			(size 0.519938 1.4986)
			(layers "F.Cu" "F.Mask" "F.Paste")
			(net "GND")
		)
		(pad "115" smd rect
			(at -2.050034 38.675056 90)
			(size 0.519938 1.4986)
			(layers "F.Cu" "F.Mask" "F.Paste")
			(net "M_G_CPU0_SB_DQS_DP<1>")
		)
		(pad "116" smd rect
			(at -2.050034 39.52494 90)
			(size 0.519938 1.4986)
			(layers "F.Cu" "F.Mask" "F.Paste")
			(net "M_G_CPU0_SB_DQS_DN<1>")
		)
		(pad "117" smd rect
			(at -2.050034 40.375078 90)
			(size 0.519938 1.4986)
			(layers "F.Cu" "F.Mask" "F.Paste")
			(net "GND")
		)
		(pad "118" smd rect
			(at -2.050034 41.224962 90)
			(size 0.519938 1.4986)
			(layers "F.Cu" "F.Mask" "F.Paste")
			(net "M_G_CPU0_SB_DQ<12>")
		)
		(pad "119" smd rect
			(at -2.050034 42.0751 90)
			(size 0.519938 1.4986)
			(layers "F.Cu" "F.Mask" "F.Paste")
			(net "GND")
		)
		(pad "120" smd rect
			(at -2.050034 42.924984 90)
			(size 0.519938 1.4986)
			(layers "F.Cu" "F.Mask" "F.Paste")
			(net "M_G_CPU0_SB_DQ<13>")
		)
		(pad "121" smd rect
			(at -2.050034 43.775122 90)
			(size 0.519938 1.4986)
			(layers "F.Cu" "F.Mask" "F.Paste")
			(net "GND")
		)
		(pad "122" smd rect
			(at -2.050034 44.625006 90)
			(size 0.519938 1.4986)
			(layers "F.Cu" "F.Mask" "F.Paste")
			(net "M_G_CPU0_SB_DQ<16>")
		)
		(pad "123" smd rect
			(at -2.050034 45.47489 90)
			(size 0.519938 1.4986)
			(layers "F.Cu" "F.Mask" "F.Paste")
			(net "GND")
		)
		(pad "124" smd rect
			(at -2.050034 46.325028 90)
			(size 0.519938 1.4986)
			(layers "F.Cu" "F.Mask" "F.Paste")
			(net "M_G_CPU0_SB_DQ<17>")
		)
		(pad "125" smd rect
			(at -2.050034 47.174912 90)
			(size 0.519938 1.4986)
			(layers "F.Cu" "F.Mask" "F.Paste")
			(net "GND")
		)
		(pad "126" smd rect
			(at -2.050034 48.02505 90)
			(size 0.519938 1.4986)
			(layers "F.Cu" "F.Mask" "F.Paste")
			(net "M_G_CPU0_SB_DQS_DP<2>")
		)
		(pad "127" smd rect
			(at -2.050034 48.874934 90)
			(size 0.519938 1.4986)
			(layers "F.Cu" "F.Mask" "F.Paste")
			(net "M_G_CPU0_SB_DQS_DN<2>")
		)
		(pad "128" smd rect
			(at -2.050034 49.725072 90)
			(size 0.519938 1.4986)
			(layers "F.Cu" "F.Mask" "F.Paste")
			(net "GND")
		)
		(pad "129" smd rect
			(at -2.050034 50.574956 90)
			(size 0.519938 1.4986)
			(layers "F.Cu" "F.Mask" "F.Paste")
			(net "M_G_CPU0_SB_DQ<20>")
		)
		(pad "130" smd rect
			(at -2.050034 51.425094 90)
			(size 0.519938 1.4986)
			(layers "F.Cu" "F.Mask" "F.Paste")
			(net "GND")
		)
		(pad "131" smd rect
			(at -2.050034 52.274978 90)
			(size 0.519938 1.4986)
			(layers "F.Cu" "F.Mask" "F.Paste")
			(net "M_G_CPU0_SB_DQ<21>")
		)
		(pad "132" smd rect
			(at -2.050034 53.125116 90)
			(size 0.519938 1.4986)
			(layers "F.Cu" "F.Mask" "F.Paste")
			(net "GND")
		)
		(pad "133" smd rect
			(at -2.050034 53.975 90)
			(size 0.519938 1.4986)
			(layers "F.Cu" "F.Mask" "F.Paste")
			(net "M_G_CPU0_SB_DQ<24>")
		)
		(pad "134" smd rect
			(at -2.050034 54.824884 90)
			(size 0.519938 1.4986)
			(layers "F.Cu" "F.Mask" "F.Paste")
			(net "GND")
		)
		(pad "135" smd rect
			(at -2.050034 55.675022 90)
			(size 0.519938 1.4986)
			(layers "F.Cu" "F.Mask" "F.Paste")
			(net "M_G_CPU0_SB_DQ<25>")
		)
		(pad "136" smd rect
			(at -2.050034 56.524906 90)
			(size 0.519938 1.4986)
			(layers "F.Cu" "F.Mask" "F.Paste")
			(net "GND")
		)
		(pad "137" smd rect
			(at -2.050034 57.375044 90)
			(size 0.519938 1.4986)
			(layers "F.Cu" "F.Mask" "F.Paste")
			(net "M_G_CPU0_SB_DQS_DP<3>")
		)
		(pad "138" smd rect
			(at -2.050034 58.224928 90)
			(size 0.519938 1.4986)
			(layers "F.Cu" "F.Mask" "F.Paste")
			(net "M_G_CPU0_SB_DQS_DN<3>")
		)
	)
)
